(kicad_pcb
	(version 20260206)
	(generator "pcbnew")
	(generator_version "10.0")
	(general
		(thickness 1.6)
		(legacy_teardrops no)
	)
	(paper "A4")
	(title_block
		(title "dpb — 14545-sa.0730WZS0815.brd")
		(comment 1 "Honey Badger (Wiwynn) / footprints 251-257 of 1066")
	)
	(layers
		(0 "F.Cu" signal "TOP")
		(4 "In1.Cu" signal "L2GND")
		(6 "In2.Cu" signal "L3")
		(8 "In3.Cu" signal "L4VCC")
		(10 "In4.Cu" signal "L5VCC")
		(12 "In5.Cu" signal "L6")
		(14 "In6.Cu" signal "L7GND")
		(2 "B.Cu" signal "BOTTOM")
		(9 "F.Adhes" user "F.Adhesive")
		(11 "B.Adhes" user "B.Adhesive")
		(13 "F.Paste" user "Package Geometry/Pastemask Top")
		(15 "B.Paste" user "Package Geometry/Pastemask Bottom")
		(5 "F.SilkS" user "Ref Des/Silkscreen Top")
		(7 "B.SilkS" user "Ref Des/Silkscreen Bottom")
		(1 "F.Mask" user "Board Geometry/Soldermask Top")
		(3 "B.Mask" user "Board Geometry/Soldermask Bottom")
		(17 "Dwgs.User" user "User.Drawings")
		(19 "Cmts.User" user "User.Comments")
		(21 "Eco1.User" user "User.Eco1")
		(23 "Eco2.User" user "User.Eco2")
		(25 "Edge.Cuts" user "Board Geometry/Outline")
		(27 "Margin" user)
		(31 "F.CrtYd" user "Package Geometry/Place Bound Top")
		(29 "B.CrtYd" user "Package Geometry/Place Bound Bottom")
		(35 "F.Fab" user "Ref Des/Assembly Top")
		(33 "B.Fab" user "Ref Des/Assembly Bottom")
	)
	(footprint ""
		(layer "F.Cu")
		(at 209.041746 -454.1647 -90)
		(property "Reference" "R337"
			(at 0 0 270)
			(layer "F.SilkS")
			(hide yes)
			(effects
				(font
					(size 1.27 1.27)
				)
			)
		)
		(property "Value" "4K7R2J-2-GP"
			(at 0.064008 -3.993896 270)
			(unlocked yes)
			(layer "F.Fab")
			(hide yes)
			(effects
				(font
					(size 1.016 1.016)
					(thickness 0.1524)
				)
			)
		)
		(property "Device Type" "R402H16"
			(at 0.064008 -5.517896 270)
			(unlocked yes)
			(layer "F.Fab")
			(hide yes)
			(effects
				(font
					(size 1.016 1.016)
					(thickness 0.1524)
				)
			)
		)
		(duplicate_pad_numbers_are_jumpers no)
		(fp_line
			(start -0.508 -0.9398)
			(end -0.508 0.9398)
			(stroke
				(width 0.1524)
				(type default)
			)
			(layer "F.SilkS")
		)
		(fp_line
			(start 0.508 -0.9398)
			(end -0.508 -0.9398)
			(stroke
				(width 0.1524)
				(type default)
			)
			(layer "F.SilkS")
		)
		(fp_rect
			(start -0.508 0.9398)
			(end 0.508 -0.9398)
			(stroke
				(width 0)
				(type default)
			)
			(fill no)
			(layer "F.CrtYd")
		)
		(fp_rect
			(start -0.508 0.9398)
			(end 0.508 -0.9398)
			(stroke
				(width 0)
				(type default)
			)
			(fill no)
			(layer "F.Fab")
		)
		(pad "1" smd custom
			(at 0 -0.4445 270)
			(size 0.1397 0.1397)
			(layers "F.Cu" "F.Mask" "F.Paste")
			(net "I2C_B_TMP3_A1")
			(options
				(clearance outline)
				(anchor circle)
			)
			(primitives
				(gr_poly
					(pts
						(arc
							(start -0.1778 -0.2794)
							(mid -0.249642 -0.249642)
							(end -0.2794 -0.1778)
						)
						(arc
							(start -0.2794 0.1778)
							(mid -0.249642 0.249642)
							(end -0.1778 0.2794)
						)
						(arc
							(start 0.1778 0.2794)
							(mid 0.249642 0.249642)
							(end 0.2794 0.1778)
						)
						(arc
							(start 0.2794 -0.1778)
							(mid 0.249642 -0.249642)
							(end 0.1778 -0.2794)
						)
					)
					(width 0)
					(fill yes)
				)
			)
		)
		(pad "2" smd custom
			(at 0 0.4445 270)
			(size 0.1397 0.1397)
			(layers "F.Cu" "F.Mask" "F.Paste")
			(net "GND")
			(options
				(clearance outline)
				(anchor circle)
			)
			(primitives
				(gr_poly
					(pts
						(arc
							(start -0.1778 -0.2794)
							(mid -0.249642 -0.249642)
							(end -0.2794 -0.1778)
						)
						(arc
							(start -0.2794 0.1778)
							(mid -0.249642 0.249642)
							(end -0.1778 0.2794)
						)
						(arc
							(start 0.1778 0.2794)
							(mid 0.249642 0.249642)
							(end 0.2794 0.1778)
						)
						(arc
							(start 0.2794 -0.1778)
							(mid 0.249642 -0.249642)
							(end 0.1778 -0.2794)
						)
					)
					(width 0)
					(fill yes)
				)
			)
		)
	)
	(footprint ""
		(layer "F.Cu")
		(at 216.084912 -82.276696 -90)
		(property "Reference" "R163"
			(at 0 0 270)
			(layer "F.SilkS")
			(hide yes)
			(effects
				(font
					(size 1.27 1.27)
				)
			)
		)
		(property "Value" "2R2010J-1-GP"
			(at 0.254 -8.0772 270)
			(unlocked yes)
			(layer "F.Fab")
			(hide yes)
			(effects
				(font
					(size 1.016 1.016)
					(thickness 0.1524)
				)
			)
		)
		(property "Device Type" "R2010H28"
			(at 0.254 -9.6774 270)
			(unlocked yes)
			(layer "F.Fab")
			(hide yes)
			(effects
				(font
					(size 1.016 1.016)
					(thickness 0.1524)
				)
			)
		)
		(duplicate_pad_numbers_are_jumpers no)
		(fp_line
			(start -1.651 3.302)
			(end 1.651 3.302)
			(stroke
				(width 0.1524)
				(type default)
			)
			(layer "F.SilkS")
		)
		(fp_line
			(start 1.651 3.302)
			(end 1.651 -3.302)
			(stroke
				(width 0.1524)
				(type default)
			)
			(layer "F.SilkS")
		)
		(fp_line
			(start -1.651 -3.302)
			(end -1.651 3.302)
			(stroke
				(width 0.1524)
				(type default)
			)
			(layer "F.SilkS")
		)
		(fp_line
			(start 1.651 -3.302)
			(end -1.651 -3.302)
			(stroke
				(width 0.1524)
				(type default)
			)
			(layer "F.SilkS")
		)
		(fp_rect
			(start -1.7272 -3.3782)
			(end 1.7272 3.3782)
			(stroke
				(width 0)
				(type default)
			)
			(fill no)
			(layer "F.CrtYd")
		)
		(fp_poly
			(pts
				(xy 1.7272 3.3782) (xy 1.7272 -3.3782) (xy -1.7272 -3.3782) (xy -1.7272 3.3782)
			)
			(stroke
				(width 0)
				(type default)
			)
			(fill no)
			(layer "F.Fab")
		)
		(pad "1" smd rect
			(at 0 -2.3495 270)
			(size 2.794 1.143)
			(layers "F.Cu" "F.Mask" "F.Paste")
			(net "12V_PRE_4")
		)
		(pad "2" smd rect
			(at 0 2.3495 270)
			(size 2.794 1.143)
			(layers "F.Cu" "F.Mask" "F.Paste")
			(net "P12V_HDD4")
		)
	)
	(footprint ""
		(layer "F.Cu")
		(at 210.946746 -454.1647 -90)
		(property "Reference" "R338"
			(at 0 0 270)
			(layer "F.SilkS")
			(hide yes)
			(effects
				(font
					(size 1.27 1.27)
				)
			)
		)
		(property "Value" "4K7R2J-2-GP"
			(at 0.064008 -3.993896 270)
			(unlocked yes)
			(layer "F.Fab")
			(hide yes)
			(effects
				(font
					(size 1.016 1.016)
					(thickness 0.1524)
				)
			)
		)
		(property "Device Type" "R402H16"
			(at 0.064008 -5.517896 270)
			(unlocked yes)
			(layer "F.Fab")
			(hide yes)
			(effects
				(font
					(size 1.016 1.016)
					(thickness 0.1524)
				)
			)
		)
		(duplicate_pad_numbers_are_jumpers no)
		(fp_line
			(start -0.508 -0.9398)
			(end -0.508 0.9398)
			(stroke
				(width 0.1524)
				(type default)
			)
			(layer "F.SilkS")
		)
		(fp_line
			(start 0.508 -0.9398)
			(end -0.508 -0.9398)
			(stroke
				(width 0.1524)
				(type default)
			)
			(layer "F.SilkS")
		)
		(fp_rect
			(start -0.508 0.9398)
			(end 0.508 -0.9398)
			(stroke
				(width 0)
				(type default)
			)
			(fill no)
			(layer "F.CrtYd")
		)
		(fp_rect
			(start -0.508 0.9398)
			(end 0.508 -0.9398)
			(stroke
				(width 0)
				(type default)
			)
			(fill no)
			(layer "F.Fab")
		)
		(pad "1" smd custom
			(at 0 -0.4445 270)
			(size 0.1397 0.1397)
			(layers "F.Cu" "F.Mask" "F.Paste")
			(net "I2C_B_TMP3_A0")
			(options
				(clearance outline)
				(anchor circle)
			)
			(primitives
				(gr_poly
					(pts
						(arc
							(start -0.1778 -0.2794)
							(mid -0.249642 -0.249642)
							(end -0.2794 -0.1778)
						)
						(arc
							(start -0.2794 0.1778)
							(mid -0.249642 0.249642)
							(end -0.1778 0.2794)
						)
						(arc
							(start 0.1778 0.2794)
							(mid 0.249642 0.249642)
							(end 0.2794 0.1778)
						)
						(arc
							(start 0.2794 -0.1778)
							(mid 0.249642 -0.249642)
							(end 0.1778 -0.2794)
						)
					)
					(width 0)
					(fill yes)
				)
			)
		)
		(pad "2" smd custom
			(at 0 0.4445 270)
			(size 0.1397 0.1397)
			(layers "F.Cu" "F.Mask" "F.Paste")
			(net "GND")
			(options
				(clearance outline)
				(anchor circle)
			)
			(primitives
				(gr_poly
					(pts
						(arc
							(start -0.1778 -0.2794)
							(mid -0.249642 -0.249642)
							(end -0.2794 -0.1778)
						)
						(arc
							(start -0.2794 0.1778)
							(mid -0.249642 0.249642)
							(end -0.1778 0.2794)
						)
						(arc
							(start 0.1778 0.2794)
							(mid 0.249642 0.249642)
							(end 0.2794 0.1778)
						)
						(arc
							(start 0.2794 -0.1778)
							(mid 0.249642 -0.249642)
							(end 0.1778 -0.2794)
						)
					)
					(width 0)
					(fill yes)
				)
			)
		)
	)
	(footprint ""
		(layer "F.Cu")
		(at 78.358746 -90.4367 90)
		(property "Reference" "R233"
			(at 0 0 90)
			(layer "F.SilkS")
			(hide yes)
			(effects
				(font
					(size 1.27 1.27)
				)
			)
		)
		(property "Value" "200KR2F-L-GP"
			(at 0.064008 -3.993896 90)
			(unlocked yes)
			(layer "F.Fab")
			(hide yes)
			(effects
				(font
					(size 1.016 1.016)
					(thickness 0.1524)
				)
			)
		)
		(property "Device Type" "R402H16"
			(at 0.064008 -5.517896 90)
			(unlocked yes)
			(layer "F.Fab")
			(hide yes)
			(effects
				(font
					(size 1.016 1.016)
					(thickness 0.1524)
				)
			)
		)
		(duplicate_pad_numbers_are_jumpers no)
		(fp_line
			(start 0.508 -0.9398)
			(end -0.508 -0.9398)
			(stroke
				(width 0.1524)
				(type default)
			)
			(layer "F.SilkS")
		)
		(fp_line
			(start -0.508 -0.9398)
			(end -0.508 0.9398)
			(stroke
				(width 0.1524)
				(type default)
			)
			(layer "F.SilkS")
		)
		(fp_rect
			(start -0.508 0.9398)
			(end 0.508 -0.9398)
			(stroke
				(width 0)
				(type default)
			)
			(fill no)
			(layer "F.CrtYd")
		)
		(fp_rect
			(start -0.508 0.9398)
			(end 0.508 -0.9398)
			(stroke
				(width 0)
				(type default)
			)
			(fill no)
			(layer "F.Fab")
		)
		(pad "1" smd custom
			(at 0 -0.4445 90)
			(size 0.1397 0.1397)
			(layers "F.Cu" "F.Mask" "F.Paste")
			(net "P12V")
			(options
				(clearance outline)
				(anchor circle)
			)
			(primitives
				(gr_poly
					(pts
						(arc
							(start -0.1778 -0.2794)
							(mid -0.249642 -0.249642)
							(end -0.2794 -0.1778)
						)
						(arc
							(start -0.2794 0.1778)
							(mid -0.249642 0.249642)
							(end -0.1778 0.2794)
						)
						(arc
							(start 0.1778 0.2794)
							(mid 0.249642 0.249642)
							(end 0.2794 0.1778)
						)
						(arc
							(start 0.2794 -0.1778)
							(mid 0.249642 -0.249642)
							(end 0.1778 -0.2794)
						)
					)
					(width 0)
					(fill yes)
				)
			)
		)
		(pad "2" smd custom
			(at 0 0.4445 90)
			(size 0.1397 0.1397)
			(layers "F.Cu" "F.Mask" "F.Paste")
			(net "SW_HDD9_P")
			(options
				(clearance outline)
				(anchor circle)
			)
			(primitives
				(gr_poly
					(pts
						(arc
							(start -0.1778 -0.2794)
							(mid -0.249642 -0.249642)
							(end -0.2794 -0.1778)
						)
						(arc
							(start -0.2794 0.1778)
							(mid -0.249642 0.249642)
							(end -0.1778 0.2794)
						)
						(arc
							(start 0.1778 0.2794)
							(mid 0.249642 0.249642)
							(end 0.2794 0.1778)
						)
						(arc
							(start 0.2794 -0.1778)
							(mid 0.249642 -0.249642)
							(end 0.1778 -0.2794)
						)
					)
					(width 0)
					(fill yes)
				)
			)
		)
	)
	(footprint ""
		(layer "F.Cu")
		(at 207.136746 -454.1647 -90)
		(property "Reference" "R336"
			(at 0 0 270)
			(layer "F.SilkS")
			(hide yes)
			(effects
				(font
					(size 1.27 1.27)
				)
			)
		)
		(property "Value" "4K7R2J-2-GP"
			(at 0.064008 -3.993896 270)
			(unlocked yes)
			(layer "F.Fab")
			(hide yes)
			(effects
				(font
					(size 1.016 1.016)
					(thickness 0.1524)
				)
			)
		)
		(property "Device Type" "R402H16"
			(at 0.064008 -5.517896 270)
			(unlocked yes)
			(layer "F.Fab")
			(hide yes)
			(effects
				(font
					(size 1.016 1.016)
					(thickness 0.1524)
				)
			)
		)
		(duplicate_pad_numbers_are_jumpers no)
		(fp_line
			(start -0.508 -0.9398)
			(end -0.508 0.9398)
			(stroke
				(width 0.1524)
				(type default)
			)
			(layer "F.SilkS")
		)
		(fp_line
			(start 0.508 -0.9398)
			(end -0.508 -0.9398)
			(stroke
				(width 0.1524)
				(type default)
			)
			(layer "F.SilkS")
		)
		(fp_rect
			(start -0.508 0.9398)
			(end 0.508 -0.9398)
			(stroke
				(width 0)
				(type default)
			)
			(fill no)
			(layer "F.CrtYd")
		)
		(fp_rect
			(start -0.508 0.9398)
			(end 0.508 -0.9398)
			(stroke
				(width 0)
				(type default)
			)
			(fill no)
			(layer "F.Fab")
		)
		(pad "1" smd custom
			(at 0 -0.4445 270)
			(size 0.1397 0.1397)
			(layers "F.Cu" "F.Mask" "F.Paste")
			(net "I2C_B_TMP3_A2")
			(options
				(clearance outline)
				(anchor circle)
			)
			(primitives
				(gr_poly
					(pts
						(arc
							(start -0.1778 -0.2794)
							(mid -0.249642 -0.249642)
							(end -0.2794 -0.1778)
						)
						(arc
							(start -0.2794 0.1778)
							(mid -0.249642 0.249642)
							(end -0.1778 0.2794)
						)
						(arc
							(start 0.1778 0.2794)
							(mid 0.249642 0.249642)
							(end 0.2794 0.1778)
						)
						(arc
							(start 0.2794 -0.1778)
							(mid 0.249642 -0.249642)
							(end 0.1778 -0.2794)
						)
					)
					(width 0)
					(fill yes)
				)
			)
		)
		(pad "2" smd custom
			(at 0 0.4445 270)
			(size 0.1397 0.1397)
			(layers "F.Cu" "F.Mask" "F.Paste")
			(net "GND")
			(options
				(clearance outline)
				(anchor circle)
			)
			(primitives
				(gr_poly
					(pts
						(arc
							(start -0.1778 -0.2794)
							(mid -0.249642 -0.249642)
							(end -0.2794 -0.1778)
						)
						(arc
							(start -0.2794 0.1778)
							(mid -0.249642 0.249642)
							(end -0.1778 0.2794)
						)
						(arc
							(start 0.1778 0.2794)
							(mid 0.249642 0.249642)
							(end 0.2794 0.1778)
						)
						(arc
							(start 0.2794 -0.1778)
							(mid 0.249642 -0.249642)
							(end 0.1778 -0.2794)
						)
					)
					(width 0)
					(fill yes)
				)
			)
		)
	)
	(footprint ""
		(layer "F.Cu")
		(at 192.786 -499.11 90)
		(property "Reference" "R478"
			(at 0 0 90)
			(layer "F.SilkS")
			(hide yes)
			(effects
				(font
					(size 1.27 1.27)
				)
			)
		)
		(property "Value" "200KR2F-L-GP"
			(at 0.064008 -3.993896 90)
			(unlocked yes)
			(layer "F.Fab")
			(hide yes)
			(effects
				(font
					(size 1.016 1.016)
					(thickness 0.1524)
				)
			)
		)
		(property "Device Type" "R402H16"
			(at 0.064008 -5.517896 90)
			(unlocked yes)
			(layer "F.Fab")
			(hide yes)
			(effects
				(font
					(size 1.016 1.016)
					(thickness 0.1524)
				)
			)
		)
		(duplicate_pad_numbers_are_jumpers no)
		(fp_line
			(start 0.508 -0.9398)
			(end -0.508 -0.9398)
			(stroke
				(width 0.1524)
				(type default)
			)
			(layer "F.SilkS")
		)
		(fp_line
			(start -0.508 -0.9398)
			(end -0.508 0.9398)
			(stroke
				(width 0.1524)
				(type default)
			)
			(layer "F.SilkS")
		)
		(fp_rect
			(start -0.508 0.9398)
			(end 0.508 -0.9398)
			(stroke
				(width 0)
				(type default)
			)
			(fill no)
			(layer "F.CrtYd")
		)
		(fp_rect
			(start -0.508 0.9398)
			(end 0.508 -0.9398)
			(stroke
				(width 0)
				(type default)
			)
			(fill no)
			(layer "F.Fab")
		)
		(pad "1" smd custom
			(at 0 -0.4445 90)
			(size 0.1397 0.1397)
			(layers "F.Cu" "F.Mask" "F.Paste")
			(net "SW_HDD0_R")
			(options
				(clearance outline)
				(anchor circle)
			)
			(primitives
				(gr_poly
					(pts
						(arc
							(start -0.1778 -0.2794)
							(mid -0.249642 -0.249642)
							(end -0.2794 -0.1778)
						)
						(arc
							(start -0.2794 0.1778)
							(mid -0.249642 0.249642)
							(end -0.1778 0.2794)
						)
						(arc
							(start 0.1778 0.2794)
							(mid 0.249642 0.249642)
							(end 0.2794 0.1778)
						)
						(arc
							(start 0.2794 -0.1778)
							(mid 0.249642 -0.249642)
							(end 0.1778 -0.2794)
						)
					)
					(width 0)
					(fill yes)
				)
			)
		)
		(pad "2" smd custom
			(at 0 0.4445 90)
			(size 0.1397 0.1397)
			(layers "F.Cu" "F.Mask" "F.Paste")
			(net "SW_HDD0_N")
			(options
				(clearance outline)
				(anchor circle)
			)
			(primitives
				(gr_poly
					(pts
						(arc
							(start -0.1778 -0.2794)
							(mid -0.249642 -0.249642)
							(end -0.2794 -0.1778)
						)
						(arc
							(start -0.2794 0.1778)
							(mid -0.249642 0.249642)
							(end -0.1778 0.2794)
						)
						(arc
							(start 0.1778 0.2794)
							(mid 0.249642 0.249642)
							(end 0.2794 0.1778)
						)
						(arc
							(start 0.2794 -0.1778)
							(mid 0.249642 -0.249642)
							(end 0.1778 -0.2794)
						)
					)
					(width 0)
					(fill yes)
				)
			)
		)
	)
	(footprint ""
		(layer "F.Cu")
		(at 5.079746 -492.7727 -90)
		(property "Reference" "R487"
			(at 0 0 270)
			(layer "F.SilkS")
			(hide yes)
			(effects
				(font
					(size 1.27 1.27)
				)
			)
		)
		(property "Value" "2K49R2F-GP"
			(at 0.064008 -3.993896 270)
			(unlocked yes)
			(layer "F.Fab")
			(hide yes)
			(effects
				(font
					(size 1.016 1.016)
					(thickness 0.1524)
				)
			)
		)
		(property "Device Type" "R402H16"
			(at 0.064008 -5.517896 270)
			(unlocked yes)
			(layer "F.Fab")
			(hide yes)
			(effects
				(font
					(size 1.016 1.016)
					(thickness 0.1524)
				)
			)
		)
		(duplicate_pad_numbers_are_jumpers no)
		(fp_line
			(start -0.508 -0.9398)
			(end -0.508 0.9398)
			(stroke
				(width 0.1524)
				(type default)
			)
			(layer "F.SilkS")
		)
		(fp_line
			(start 0.508 -0.9398)
			(end -0.508 -0.9398)
			(stroke
				(width 0.1524)
				(type default)
			)
			(layer "F.SilkS")
		)
		(fp_rect
			(start -0.508 0.9398)
			(end 0.508 -0.9398)
			(stroke
				(width 0)
				(type default)
			)
			(fill no)
			(layer "F.CrtYd")
		)
		(fp_rect
			(start -0.508 0.9398)
			(end 0.508 -0.9398)
			(stroke
				(width 0)
				(type default)
			)
			(fill no)
			(layer "F.Fab")
		)
		(pad "1" smd custom
			(at 0 -0.4445 270)
			(size 0.1397 0.1397)
			(layers "F.Cu" "F.Mask" "F.Paste")
			(net "P5VC_EN")
			(options
				(clearance outline)
				(anchor circle)
			)
			(primitives
				(gr_poly
					(pts
						(arc
							(start -0.1778 -0.2794)
							(mid -0.249642 -0.249642)
							(end -0.2794 -0.1778)
						)
						(arc
							(start -0.2794 0.1778)
							(mid -0.249642 0.249642)
							(end -0.1778 0.2794)
						)
						(arc
							(start 0.1778 0.2794)
							(mid 0.249642 0.249642)
							(end 0.2794 0.1778)
						)
						(arc
							(start 0.2794 -0.1778)
							(mid 0.249642 -0.249642)
							(end 0.1778 -0.2794)
						)
					)
					(width 0)
					(fill yes)
				)
			)
		)
		(pad "2" smd custom
			(at 0 0.4445 270)
			(size 0.1397 0.1397)
			(layers "F.Cu" "F.Mask" "F.Paste")
			(net "GND")
			(options
				(clearance outline)
				(anchor circle)
			)
			(primitives
				(gr_poly
					(pts
						(arc
							(start -0.1778 -0.2794)
							(mid -0.249642 -0.249642)
							(end -0.2794 -0.1778)
						)
						(arc
							(start -0.2794 0.1778)
							(mid -0.249642 0.249642)
							(end -0.1778 0.2794)
						)
						(arc
							(start 0.1778 0.2794)
							(mid 0.249642 0.249642)
							(end 0.2794 0.1778)
						)
						(arc
							(start 0.2794 -0.1778)
							(mid 0.249642 -0.249642)
							(end 0.1778 -0.2794)
						)
					)
					(width 0)
					(fill yes)
				)
			)
		)
	)
)
